(kicad_pcb
	(version 20260206)
	(generator "pcbnew")
	(generator_version "10.0")
	(general
		(thickness 1.6)
		(legacy_teardrops no)
	)
	(paper "A4")
	(title_block
		(title "04192023_DAF0TMB3IC0_F0TG_MB_C_brd_V02_OCP.brd")
		(comment 1 "Grand Teton / footprints 2385-2391 of 8354")
	)
	(layers
		(0 "F.Cu" signal "TOP")
		(4 "In1.Cu" signal "GND")
		(6 "In2.Cu" signal "IN1")
		(8 "In3.Cu" signal "GND1")
		(10 "In4.Cu" signal "IN2")
		(12 "In5.Cu" signal "GND2")
		(14 "In6.Cu" signal "IN3")
		(16 "In7.Cu" signal "GND3")
		(18 "In8.Cu" signal "VCC")
		(20 "In9.Cu" signal "VCC1")
		(22 "In10.Cu" signal "GND4")
		(24 "In11.Cu" signal "IN4")
		(26 "In12.Cu" signal "GND5")
		(28 "In13.Cu" signal "IN5")
		(30 "In14.Cu" signal "GND6")
		(32 "In15.Cu" signal "IN6")
		(34 "In16.Cu" signal "GND7")
		(2 "B.Cu" signal "BOTTOM")
		(9 "F.Adhes" user "F.Adhesive")
		(11 "B.Adhes" user "B.Adhesive")
		(13 "F.Paste" user "Package Geometry/Pastemask Top")
		(15 "B.Paste" user "Package Geometry/Pastemask Bottom")
		(5 "F.SilkS" user "Ref Des/Silkscreen Top")
		(7 "B.SilkS" user "Ref Des/Silkscreen Bottom")
		(1 "F.Mask" user "Board Geometry/Soldermask Top")
		(3 "B.Mask" user "Board Geometry/Soldermask Bottom")
		(17 "Dwgs.User" user "User.Drawings")
		(19 "Cmts.User" user "User.Comments")
		(21 "Eco1.User" user "User.Eco1")
		(23 "Eco2.User" user "User.Eco2")
		(25 "Edge.Cuts" user "Board Geometry/Outline")
		(27 "Margin" user)
		(31 "F.CrtYd" user "Package Geometry/Place Bound Top")
		(29 "B.CrtYd" user "Package Geometry/Place Bound Bottom")
		(35 "F.Fab" user "Ref Des/Assembly Top")
		(33 "B.Fab" user "Ref Des/Assembly Bottom")
	)
	(footprint ""
		(layer "F.Cu")
		(at 101.760528 -36.25215 90)
		(property "Reference" "R6325"
			(at 0 0 90)
			(layer "F.SilkS")
			(hide yes)
			(effects
				(font
					(size 1.27 1.27)
				)
			)
		)
		(property "Value" ""
			(at 0 0 90)
			(layer "F.Fab")
			(effects
				(font
					(size 1.27 1.27)
				)
			)
		)
		(duplicate_pad_numbers_are_jumpers no)
		(fp_line
			(start 0.7874 -0.4064)
			(end 0.7874 0.4064)
			(stroke
				(width 0.1524)
				(type default)
			)
			(layer "F.SilkS")
		)
		(fp_line
			(start -0.7874 -0.4064)
			(end 0.7874 -0.4064)
			(stroke
				(width 0.1524)
				(type default)
			)
			(layer "F.SilkS")
		)
		(fp_line
			(start 0.7874 0.4064)
			(end -0.7874 0.4064)
			(stroke
				(width 0.1524)
				(type default)
			)
			(layer "F.SilkS")
		)
		(fp_line
			(start -0.7874 0.4064)
			(end -0.7874 -0.4064)
			(stroke
				(width 0.1524)
				(type default)
			)
			(layer "F.SilkS")
		)
		(fp_line
			(start -0.12065 -0.305054)
			(end -0.12065 -0.2794)
			(stroke
				(width 0.1)
				(type default)
			)
			(layer "F.Fab")
		)
		(fp_line
			(start -0.67945 -0.305054)
			(end -0.12065 -0.305054)
			(stroke
				(width 0.1)
				(type default)
			)
			(layer "F.Fab")
		)
		(fp_line
			(start 0.67945 -0.3048)
			(end 0.67945 0.3048)
			(stroke
				(width 0.1)
				(type default)
			)
			(layer "F.Fab")
		)
		(fp_line
			(start 0.12065 -0.3048)
			(end 0.67945 -0.3048)
			(stroke
				(width 0.1)
				(type default)
			)
			(layer "F.Fab")
		)
		(fp_line
			(start 0.12065 -0.2794)
			(end 0.12065 -0.3048)
			(stroke
				(width 0.1)
				(type default)
			)
			(layer "F.Fab")
		)
		(fp_line
			(start -0.12065 -0.2794)
			(end 0.12065 -0.2794)
			(stroke
				(width 0.1)
				(type default)
			)
			(layer "F.Fab")
		)
		(fp_line
			(start 0.120396 0.2794)
			(end -0.12065 0.2794)
			(stroke
				(width 0.1)
				(type default)
			)
			(layer "F.Fab")
		)
		(fp_line
			(start -0.12065 0.2794)
			(end -0.12065 0.3048)
			(stroke
				(width 0.1)
				(type default)
			)
			(layer "F.Fab")
		)
		(fp_line
			(start 0.67945 0.3048)
			(end 0.120396 0.3048)
			(stroke
				(width 0.1)
				(type default)
			)
			(layer "F.Fab")
		)
		(fp_line
			(start 0.120396 0.3048)
			(end 0.120396 0.2794)
			(stroke
				(width 0.1)
				(type default)
			)
			(layer "F.Fab")
		)
		(fp_line
			(start -0.12065 0.3048)
			(end -0.67945 0.3048)
			(stroke
				(width 0.1)
				(type default)
			)
			(layer "F.Fab")
		)
		(fp_line
			(start -0.67945 0.3048)
			(end -0.67945 -0.305054)
			(stroke
				(width 0.1)
				(type default)
			)
			(layer "F.Fab")
		)
		(pad "1" smd circle
			(at -0.40005 0 90)
			(size 0 0)
			(layers "F.Cu" "F.Mask" "F.Paste")
			(net "USB_HUB2_TI_TEST")
		)
		(pad "2" smd circle
			(at 0.40005 0 90)
			(size 0 0)
			(layers "F.Cu" "F.Mask" "F.Paste")
			(net "GND")
		)
	)
	(footprint ""
		(layer "F.Cu")
		(at 368.241326 -45.267118 -90)
		(property "Reference" "R816"
			(at 0 0 270)
			(layer "F.SilkS")
			(hide yes)
			(effects
				(font
					(size 1.27 1.27)
				)
			)
		)
		(property "Value" ""
			(at 0 0 270)
			(layer "F.Fab")
			(effects
				(font
					(size 1.27 1.27)
				)
			)
		)
		(duplicate_pad_numbers_are_jumpers no)
		(fp_line
			(start -0.7874 0.4064)
			(end -0.7874 -0.4064)
			(stroke
				(width 0.1524)
				(type default)
			)
			(layer "F.SilkS")
		)
		(fp_line
			(start 0.7874 0.4064)
			(end -0.7874 0.4064)
			(stroke
				(width 0.1524)
				(type default)
			)
			(layer "F.SilkS")
		)
		(fp_line
			(start -0.7874 -0.4064)
			(end 0.7874 -0.4064)
			(stroke
				(width 0.1524)
				(type default)
			)
			(layer "F.SilkS")
		)
		(fp_line
			(start 0.7874 -0.4064)
			(end 0.7874 0.4064)
			(stroke
				(width 0.1524)
				(type default)
			)
			(layer "F.SilkS")
		)
		(fp_line
			(start -0.67945 0.3048)
			(end -0.67945 -0.305054)
			(stroke
				(width 0.1)
				(type default)
			)
			(layer "F.Fab")
		)
		(fp_line
			(start -0.12065 0.3048)
			(end -0.67945 0.3048)
			(stroke
				(width 0.1)
				(type default)
			)
			(layer "F.Fab")
		)
		(fp_line
			(start 0.120396 0.3048)
			(end 0.120396 0.2794)
			(stroke
				(width 0.1)
				(type default)
			)
			(layer "F.Fab")
		)
		(fp_line
			(start 0.67945 0.3048)
			(end 0.120396 0.3048)
			(stroke
				(width 0.1)
				(type default)
			)
			(layer "F.Fab")
		)
		(fp_line
			(start -0.12065 0.2794)
			(end -0.12065 0.3048)
			(stroke
				(width 0.1)
				(type default)
			)
			(layer "F.Fab")
		)
		(fp_line
			(start 0.120396 0.2794)
			(end -0.12065 0.2794)
			(stroke
				(width 0.1)
				(type default)
			)
			(layer "F.Fab")
		)
		(fp_line
			(start -0.12065 -0.2794)
			(end 0.12065 -0.2794)
			(stroke
				(width 0.1)
				(type default)
			)
			(layer "F.Fab")
		)
		(fp_line
			(start 0.12065 -0.2794)
			(end 0.12065 -0.3048)
			(stroke
				(width 0.1)
				(type default)
			)
			(layer "F.Fab")
		)
		(fp_line
			(start 0.12065 -0.3048)
			(end 0.67945 -0.3048)
			(stroke
				(width 0.1)
				(type default)
			)
			(layer "F.Fab")
		)
		(fp_line
			(start 0.67945 -0.3048)
			(end 0.67945 0.3048)
			(stroke
				(width 0.1)
				(type default)
			)
			(layer "F.Fab")
		)
		(fp_line
			(start -0.67945 -0.305054)
			(end -0.12065 -0.305054)
			(stroke
				(width 0.1)
				(type default)
			)
			(layer "F.Fab")
		)
		(fp_line
			(start -0.12065 -0.305054)
			(end -0.12065 -0.2794)
			(stroke
				(width 0.1)
				(type default)
			)
			(layer "F.Fab")
		)
		(pad "1" smd circle
			(at -0.40005 0 270)
			(size 0 0)
			(layers "F.Cu" "F.Mask" "F.Paste")
			(net "PVDD18_S5_P0")
		)
		(pad "2" smd circle
			(at 0.40005 0 270)
			(size 0 0)
			(layers "F.Cu" "F.Mask" "F.Paste")
			(net "UART_CPU0_SCM_UART1_RX")
		)
	)
	(footprint ""
		(layer "F.Cu")
		(at 6.673088 -373.44985 -90)
		(property "Reference" "PC6632"
			(at 4.41452 2.228088 0)
			(unlocked yes)
			(layer "F.SilkS")
			(effects
				(font
					(size 0.7874 0.5842)
					(thickness 0.1524)
				)
				(justify left)
			)
		)
		(property "Value" ""
			(at 0 0 270)
			(layer "F.Fab")
			(effects
				(font
					(size 1.27 1.27)
				)
			)
		)
		(duplicate_pad_numbers_are_jumpers no)
		(fp_line
			(start -1.988058 2.750058)
			(end 2.750058 2.750058)
			(stroke
				(width 0.1524)
				(type default)
			)
			(layer "F.SilkS")
		)
		(fp_line
			(start 2.750058 2.750058)
			(end 2.750058 0.9398)
			(stroke
				(width 0.1524)
				(type default)
			)
			(layer "F.SilkS")
		)
		(fp_line
			(start -2.750058 1.988058)
			(end -1.988058 2.750058)
			(stroke
				(width 0.1524)
				(type default)
			)
			(layer "F.SilkS")
		)
		(fp_line
			(start -2.750058 0.9398)
			(end -2.750058 1.988058)
			(stroke
				(width 0.1524)
				(type default)
			)
			(layer "F.SilkS")
		)
		(fp_line
			(start 2.750058 -0.9398)
			(end 2.750058 -2.750058)
			(stroke
				(width 0.1524)
				(type default)
			)
			(layer "F.SilkS")
		)
		(fp_line
			(start -2.750058 -1.988058)
			(end -2.750058 -0.9398)
			(stroke
				(width 0.1524)
				(type default)
			)
			(layer "F.SilkS")
		)
		(fp_line
			(start -1.988058 -2.750058)
			(end -2.750058 -1.988058)
			(stroke
				(width 0.1524)
				(type default)
			)
			(layer "F.SilkS")
		)
		(fp_line
			(start 2.750058 -2.750058)
			(end -1.988058 -2.750058)
			(stroke
				(width 0.1524)
				(type default)
			)
			(layer "F.SilkS")
		)
		(fp_line
			(start -2.750058 2.750058)
			(end 2.750058 2.750058)
			(stroke
				(width 0.1)
				(type default)
			)
			(layer "F.Fab")
		)
		(fp_line
			(start 2.750058 2.750058)
			(end 2.750058 -2.750058)
			(stroke
				(width 0.1)
				(type default)
			)
			(layer "F.Fab")
		)
		(fp_line
			(start -2.750058 -2.750058)
			(end -2.750058 2.750058)
			(stroke
				(width 0.1)
				(type default)
			)
			(layer "F.Fab")
		)
		(fp_line
			(start 2.750058 -2.750058)
			(end -2.750058 -2.750058)
			(stroke
				(width 0.1)
				(type default)
			)
			(layer "F.Fab")
		)
		(pad "1" smd rect
			(at -2.199894 0)
			(size 1.6002 3.0226)
			(layers "F.Cu" "F.Mask" "F.Paste")
			(net "P0V9_CPU1_RT_2D")
		)
		(pad "2" smd rect
			(at 2.199894 0)
			(size 1.6002 3.0226)
			(layers "F.Cu" "F.Mask" "F.Paste")
			(net "GND")
		)
	)
	(footprint ""
		(layer "F.Cu")
		(at 353.900232 -260.305042)
		(property "Reference" "C2141"
			(at 0 0 0)
			(layer "F.SilkS")
			(hide yes)
			(effects
				(font
					(size 1.27 1.27)
				)
			)
		)
		(property "Value" ""
			(at 0 0 0)
			(layer "F.Fab")
			(effects
				(font
					(size 1.27 1.27)
				)
			)
		)
		(duplicate_pad_numbers_are_jumpers no)
		(fp_line
			(start -0.7874 -0.4064)
			(end 0.7874 -0.4064)
			(stroke
				(width 0.1524)
				(type default)
			)
			(layer "F.SilkS")
		)
		(fp_line
			(start -0.7874 0.4064)
			(end -0.7874 -0.4064)
			(stroke
				(width 0.1524)
				(type default)
			)
			(layer "F.SilkS")
		)
		(fp_line
			(start 0.7874 -0.4064)
			(end 0.7874 0.4064)
			(stroke
				(width 0.1524)
				(type default)
			)
			(layer "F.SilkS")
		)
		(fp_line
			(start 0.7874 0.4064)
			(end -0.7874 0.4064)
			(stroke
				(width 0.1524)
				(type default)
			)
			(layer "F.SilkS")
		)
		(fp_line
			(start -0.67945 -0.305054)
			(end -0.12065 -0.305054)
			(stroke
				(width 0.1)
				(type default)
			)
			(layer "F.Fab")
		)
		(fp_line
			(start -0.67945 0.3048)
			(end -0.67945 -0.305054)
			(stroke
				(width 0.1)
				(type default)
			)
			(layer "F.Fab")
		)
		(fp_line
			(start -0.12065 -0.305054)
			(end -0.12065 -0.2794)
			(stroke
				(width 0.1)
				(type default)
			)
			(layer "F.Fab")
		)
		(fp_line
			(start -0.12065 -0.2794)
			(end 0.12065 -0.2794)
			(stroke
				(width 0.1)
				(type default)
			)
			(layer "F.Fab")
		)
		(fp_line
			(start -0.12065 0.2794)
			(end -0.12065 0.3048)
			(stroke
				(width 0.1)
				(type default)
			)
			(layer "F.Fab")
		)
		(fp_line
			(start -0.12065 0.3048)
			(end -0.67945 0.3048)
			(stroke
				(width 0.1)
				(type default)
			)
			(layer "F.Fab")
		)
		(fp_line
			(start 0.120396 0.2794)
			(end -0.12065 0.2794)
			(stroke
				(width 0.1)
				(type default)
			)
			(layer "F.Fab")
		)
		(fp_line
			(start 0.120396 0.3048)
			(end 0.120396 0.2794)
			(stroke
				(width 0.1)
				(type default)
			)
			(layer "F.Fab")
		)
		(fp_line
			(start 0.12065 -0.3048)
			(end 0.67945 -0.3048)
			(stroke
				(width 0.1)
				(type default)
			)
			(layer "F.Fab")
		)
		(fp_line
			(start 0.12065 -0.2794)
			(end 0.12065 -0.3048)
			(stroke
				(width 0.1)
				(type default)
			)
			(layer "F.Fab")
		)
		(fp_line
			(start 0.67945 -0.3048)
			(end 0.67945 0.3048)
			(stroke
				(width 0.1)
				(type default)
			)
			(layer "F.Fab")
		)
		(fp_line
			(start 0.67945 0.3048)
			(end 0.120396 0.3048)
			(stroke
				(width 0.1)
				(type default)
			)
			(layer "F.Fab")
		)
		(pad "1" smd circle
			(at -0.40005 0)
			(size 0 0)
			(layers "F.Cu" "F.Mask" "F.Paste")
			(net "PVDDIO_P0")
		)
		(pad "2" smd circle
			(at 0.40005 0)
			(size 0 0)
			(layers "F.Cu" "F.Mask" "F.Paste")
			(net "GND")
		)
	)
	(footprint ""
		(layer "F.Cu")
		(at 146.27479 -57.275984 -90)
		(property "Reference" "U147"
			(at 1.504188 2.769108 90)
			(unlocked yes)
			(layer "F.SilkS")
			(effects
				(font
					(size 0.7874 0.5842)
					(thickness 0.1524)
				)
				(justify left)
			)
		)
		(property "Value" ""
			(at 0 0 270)
			(layer "F.Fab")
			(effects
				(font
					(size 1.27 1.27)
				)
			)
		)
		(duplicate_pad_numbers_are_jumpers no)
		(fp_line
			(start -1.245616 1.445768)
			(end -1.245616 -1.445768)
			(stroke
				(width 0.1524)
				(type default)
			)
			(layer "F.SilkS")
		)
		(fp_line
			(start 1.245616 1.445768)
			(end -1.245616 1.445768)
			(stroke
				(width 0.1524)
				(type default)
			)
			(layer "F.SilkS")
		)
		(fp_line
			(start -1.245616 -1.445768)
			(end 1.245616 -1.445768)
			(stroke
				(width 0.1524)
				(type default)
			)
			(layer "F.SilkS")
		)
		(fp_line
			(start 1.245616 -1.445768)
			(end 1.245616 1.445768)
			(stroke
				(width 0.1524)
				(type default)
			)
			(layer "F.SilkS")
		)
		(fp_poly
			(pts
				(xy -1.386586 -0.199898) (xy -1.894586 0.054102) (xy -1.894586 -0.453898)
			)
			(stroke
				(width 0)
				(type default)
			)
			(fill yes)
			(layer "F.SilkS")
		)
		(fp_line
			(start -0.724916 0.925068)
			(end -0.724916 -0.925068)
			(stroke
				(width 0.1)
				(type default)
			)
			(layer "F.Fab")
		)
		(fp_line
			(start 0.724916 0.925068)
			(end -0.724916 0.925068)
			(stroke
				(width 0.1)
				(type default)
			)
			(layer "F.Fab")
		)
		(fp_line
			(start -0.724916 -0.925068)
			(end 0.724916 -0.925068)
			(stroke
				(width 0.1)
				(type default)
			)
			(layer "F.Fab")
		)
		(fp_line
			(start 0.724916 -0.925068)
			(end 0.724916 0.925068)
			(stroke
				(width 0.1)
				(type default)
			)
			(layer "F.Fab")
		)
		(fp_poly
			(pts
				(xy -1.894586 -0.453898) (xy -1.894586 0.054102) (xy -1.386586 -0.199898)
			)
			(stroke
				(width 0)
				(type default)
			)
			(fill yes)
			(layer "F.Fab")
		)
		(pad "1" smd circle
			(at -0.649986 -0.199898 180)
			(size 0 0)
			(layers "F.Cu" "F.Mask" "F.Paste")
			(net "GND")
		)
		(pad "2" smd rect
			(at -0.700024 0.199898)
			(size 0.1778 0.8128)
			(layers "F.Cu" "F.Mask" "F.Paste")
			(net "JTAG_BMC_OE_N")
		)
		(pad "3" smd rect
			(at -0.40005 0.899922 270)
			(size 0.1778 0.8128)
			(layers "F.Cu" "F.Mask" "F.Paste")
			(net "GND")
		)
		(pad "4" smd rect
			(at 0 0.899922 270)
			(size 0.1778 0.8128)
			(layers "F.Cu" "F.Mask" "F.Paste")
			(net "JTAG_TDO_R1")
		)
		(pad "5" smd rect
			(at 0.40005 0.899922 270)
			(size 0.1778 0.8128)
			(layers "F.Cu" "F.Mask" "F.Paste")
			(net "JTAG_TDI_R")
		)
		(pad "6" smd rect
			(at 0.700024 0.199898 180)
			(size 0.1778 0.8128)
			(layers "F.Cu" "F.Mask" "F.Paste")
			(net "PVDD18_S5_P0")
		)
		(pad "7" smd rect
			(at 0.700024 -0.199898 180)
			(size 0.1778 0.8128)
			(layers "F.Cu" "F.Mask" "F.Paste")
			(net "P3V3_AUX")
		)
		(pad "8" smd rect
			(at 0.40005 -0.899922 270)
			(size 0.1778 0.8128)
			(layers "F.Cu" "F.Mask" "F.Paste")
			(net "JTAG_SCM_MUX_TDO")
		)
		(pad "9" smd rect
			(at 0 -0.899922 270)
			(size 0.1778 0.8128)
			(layers "F.Cu" "F.Mask" "F.Paste")
			(net "JTAG_SCM_MUX_TDI")
		)
		(pad "10" smd rect
			(at -0.40005 -0.912622 270)
			(size 0.1778 0.7874)
			(layers "F.Cu" "F.Mask" "F.Paste")
			(net "P3V3_AUX")
		)
	)
	(footprint ""
		(layer "F.Cu")
		(at 392.962384 -392.48588 180)
		(property "Reference" "R1086"
			(at 0 0 180)
			(layer "F.SilkS")
			(hide yes)
			(effects
				(font
					(size 1.27 1.27)
				)
			)
		)
		(property "Value" ""
			(at 0 0 180)
			(layer "F.Fab")
			(effects
				(font
					(size 1.27 1.27)
				)
			)
		)
		(duplicate_pad_numbers_are_jumpers no)
		(fp_line
			(start 0.7874 0.4064)
			(end -0.7874 0.4064)
			(stroke
				(width 0.1524)
				(type default)
			)
			(layer "F.SilkS")
		)
		(fp_line
			(start 0.7874 -0.4064)
			(end 0.7874 0.4064)
			(stroke
				(width 0.1524)
				(type default)
			)
			(layer "F.SilkS")
		)
		(fp_line
			(start -0.7874 0.4064)
			(end -0.7874 -0.4064)
			(stroke
				(width 0.1524)
				(type default)
			)
			(layer "F.SilkS")
		)
		(fp_line
			(start -0.7874 -0.4064)
			(end 0.7874 -0.4064)
			(stroke
				(width 0.1524)
				(type default)
			)
			(layer "F.SilkS")
		)
		(fp_line
			(start 0.67945 0.3048)
			(end 0.120396 0.3048)
			(stroke
				(width 0.1)
				(type default)
			)
			(layer "F.Fab")
		)
		(fp_line
			(start 0.67945 -0.3048)
			(end 0.67945 0.3048)
			(stroke
				(width 0.1)
				(type default)
			)
			(layer "F.Fab")
		)
		(fp_line
			(start 0.12065 -0.2794)
			(end 0.12065 -0.3048)
			(stroke
				(width 0.1)
				(type default)
			)
			(layer "F.Fab")
		)
		(fp_line
			(start 0.12065 -0.3048)
			(end 0.67945 -0.3048)
			(stroke
				(width 0.1)
				(type default)
			)
			(layer "F.Fab")
		)
		(fp_line
			(start 0.120396 0.3048)
			(end 0.120396 0.2794)
			(stroke
				(width 0.1)
				(type default)
			)
			(layer "F.Fab")
		)
		(fp_line
			(start 0.120396 0.2794)
			(end -0.12065 0.2794)
			(stroke
				(width 0.1)
				(type default)
			)
			(layer "F.Fab")
		)
		(fp_line
			(start -0.12065 0.3048)
			(end -0.67945 0.3048)
			(stroke
				(width 0.1)
				(type default)
			)
			(layer "F.Fab")
		)
		(fp_line
			(start -0.12065 0.2794)
			(end -0.12065 0.3048)
			(stroke
				(width 0.1)
				(type default)
			)
			(layer "F.Fab")
		)
		(fp_line
			(start -0.12065 -0.2794)
			(end 0.12065 -0.2794)
			(stroke
				(width 0.1)
				(type default)
			)
			(layer "F.Fab")
		)
		(fp_line
			(start -0.12065 -0.305054)
			(end -0.12065 -0.2794)
			(stroke
				(width 0.1)
				(type default)
			)
			(layer "F.Fab")
		)
		(fp_line
			(start -0.67945 0.3048)
			(end -0.67945 -0.305054)
			(stroke
				(width 0.1)
				(type default)
			)
			(layer "F.Fab")
		)
		(fp_line
			(start -0.67945 -0.305054)
			(end -0.12065 -0.305054)
			(stroke
				(width 0.1)
				(type default)
			)
			(layer "F.Fab")
		)
		(pad "1" smd rect
			(at -0.40005 0)
			(size 0.4572 0.508)
			(layers "F.Cu" "F.Mask" "F.Paste")
			(net "P1V8_CPU0_RT3_1A_1D")
		)
		(pad "2" smd rect
			(at 0.40005 0)
			(size 0.4572 0.508)
			(layers "F.Cu" "F.Mask" "F.Paste")
			(net "P1V8_CPU0_RT3_1A")
		)
	)
	(footprint ""
		(layer "F.Cu")
		(at 103.185722 -28.422854 -90)
		(property "Reference" "R346"
			(at 0 0 270)
			(layer "F.SilkS")
			(hide yes)
			(effects
				(font
					(size 1.27 1.27)
				)
			)
		)
		(property "Value" ""
			(at 0 0 270)
			(layer "F.Fab")
			(effects
				(font
					(size 1.27 1.27)
				)
			)
		)
		(duplicate_pad_numbers_are_jumpers no)
		(fp_line
			(start -0.32512 0.175006)
			(end -0.32512 -0.175006)
			(stroke
				(width 0.1)
				(type default)
			)
			(layer "F.Fab")
		)
		(fp_line
			(start 0.32512 0.175006)
			(end -0.32512 0.175006)
			(stroke
				(width 0.1)
				(type default)
			)
			(layer "F.Fab")
		)
		(fp_line
			(start -0.32512 -0.175006)
			(end 0.32512 -0.175006)
			(stroke
				(width 0.1)
				(type default)
			)
			(layer "F.Fab")
		)
		(fp_line
			(start 0.32512 -0.175006)
			(end 0.32512 0.175006)
			(stroke
				(width 0.1)
				(type default)
			)
			(layer "F.Fab")
		)
		(pad "1" smd rect
			(at -0.2667 0 270)
			(size 0.3048 0.381)
			(layers "F.Cu" "F.Mask" "F.Paste")
			(net "USB3_CPU0_BMC_TX_C2_DN")
		)
		(pad "2" smd rect
			(at 0.2667 0 90)
			(size 0.3048 0.381)
			(layers "F.Cu" "F.Mask" "F.Paste")
			(net "GND")
		)
	)
)
